# S9S_MB_2U (Grand Teton) — schematic netlist excerpt (pin names and nets, part order shuffled) for the footprints in the layout excerpt that follows; sources: Cadence DE-HDL packaged netlist, KiCad conversion of 03242023_DA0F0TMBIJ0_F0T_Motherboard_J_brd_V01_OCP.brd

C2047  Q_CAP  0.1UF 25V 10% X7R  pkg 0402  page 250 : A = P3V3_AUX_ADC_TIC ; B = GND

U335  74LVC1G08W57  74LVC1G08W5-7 IC  pkg SOT25-5_0-95_3X1-6  page 164
  A  = HP_LVC3_OCP_V3_2_PWRGD_R2
  B  = OCP_V3_2_AUX_PWR_PLD_EN_R
  GND  = GND
  Y  = OCP_V3_2_AUX_PWR_EN_R2
  VCC  = P3V3_AUX

(kicad_pcb
	(version 20260206)
	(generator "pcbnew")
	(generator_version "10.0")
	(general
		(thickness 1.6)
		(legacy_teardrops no)
	)
	(paper "A4")
	(title_block
		(title "03242023_DA0F0TMBIJ0_F0T_Motherboard_J_brd_V01_OCP.brd")
		(comment 1 "Grand Teton / footprints 2579-2580 of 6105")
	)
	(layers
		(0 "F.Cu" signal "TOP")
		(4 "In1.Cu" signal "GND")
		(6 "In2.Cu" signal "IN1")
		(8 "In3.Cu" signal "GND1")
		(10 "In4.Cu" signal "IN2")
		(12 "In5.Cu" signal "GND2")
		(14 "In6.Cu" signal "IN3")
		(16 "In7.Cu" signal "GND3")
		(18 "In8.Cu" signal "VCC")
		(20 "In9.Cu" signal "VCC1")
		(22 "In10.Cu" signal "GND4")
		(24 "In11.Cu" signal "IN4")
		(26 "In12.Cu" signal "GND5")
		(28 "In13.Cu" signal "IN5")
		(30 "In14.Cu" signal "GND6")
		(32 "In15.Cu" signal "IN6")
		(34 "In16.Cu" signal "GND7")
		(2 "B.Cu" signal "BOTTOM")
		(9 "F.Adhes" user "F.Adhesive")
		(11 "B.Adhes" user "B.Adhesive")
		(13 "F.Paste" user "Package Geometry/Pastemask Top")
		(15 "B.Paste" user "Package Geometry/Pastemask Bottom")
		(5 "F.SilkS" user "Ref Des/Silkscreen Top")
		(7 "B.SilkS" user "Ref Des/Silkscreen Bottom")
		(1 "F.Mask" user "Board Geometry/Soldermask Top")
		(3 "B.Mask" user "Board Geometry/Soldermask Bottom")
		(17 "Dwgs.User" user "User.Drawings")
		(19 "Cmts.User" user "User.Comments")
		(21 "Eco1.User" user "User.Eco1")
		(23 "Eco2.User" user "User.Eco2")
		(25 "Edge.Cuts" user "Board Geometry/Outline")
		(27 "Margin" user)
		(31 "F.CrtYd" user "Package Geometry/Place Bound Top")
		(29 "B.CrtYd" user "Package Geometry/Place Bound Bottom")
		(35 "F.Fab" user "Ref Des/Assembly Top")
		(33 "B.Fab" user "Ref Des/Assembly Bottom")
	)
	(footprint ""
		(layer "F.Cu")
		(at 36.930584 -107.539282)
		(property "Reference" "C2047"
			(at 0 0 0)
			(layer "F.SilkS")
			(hide yes)
			(effects
				(font
					(size 1.27 1.27)
				)
			)
		)
		(property "Value" ""
			(at 0 0 0)
			(layer "F.Fab")
			(effects
				(font
					(size 1.27 1.27)
				)
			)
		)
		(duplicate_pad_numbers_are_jumpers no)
		(fp_line
			(start -0.7874 -0.4064)
			(end 0.7874 -0.4064)
			(stroke
				(width 0.1524)
				(type default)
			)
			(layer "F.SilkS")
		)
		(fp_line
			(start -0.7874 0.4064)
			(end -0.7874 -0.4064)
			(stroke
				(width 0.1524)
				(type default)
			)
			(layer "F.SilkS")
		)
		(fp_line
			(start 0.7874 -0.4064)
			(end 0.7874 0.4064)
			(stroke
				(width 0.1524)
				(type default)
			)
			(layer "F.SilkS")
		)
		(fp_line
			(start 0.7874 0.4064)
			(end -0.7874 0.4064)
			(stroke
				(width 0.1524)
				(type default)
			)
			(layer "F.SilkS")
		)
		(fp_line
			(start -0.67945 -0.305054)
			(end -0.12065 -0.305054)
			(stroke
				(width 0.1)
				(type default)
			)
			(layer "F.Fab")
		)
		(fp_line
			(start -0.67945 0.3048)
			(end -0.67945 -0.305054)
			(stroke
				(width 0.1)
				(type default)
			)
			(layer "F.Fab")
		)
		(fp_line
			(start -0.12065 -0.305054)
			(end -0.12065 -0.2794)
			(stroke
				(width 0.1)
				(type default)
			)
			(layer "F.Fab")
		)
		(fp_line
			(start -0.12065 -0.2794)
			(end 0.12065 -0.2794)
			(stroke
				(width 0.1)
				(type default)
			)
			(layer "F.Fab")
		)
		(fp_line
			(start -0.12065 0.2794)
			(end -0.12065 0.3048)
			(stroke
				(width 0.1)
				(type default)
			)
			(layer "F.Fab")
		)
		(fp_line
			(start -0.12065 0.3048)
			(end -0.67945 0.3048)
			(stroke
				(width 0.1)
				(type default)
			)
			(layer "F.Fab")
		)
		(fp_line
			(start 0.120396 0.2794)
			(end -0.12065 0.2794)
			(stroke
				(width 0.1)
				(type default)
			)
			(layer "F.Fab")
		)
		(fp_line
			(start 0.120396 0.3048)
			(end 0.120396 0.2794)
			(stroke
				(width 0.1)
				(type default)
			)
			(layer "F.Fab")
		)
		(fp_line
			(start 0.12065 -0.3048)
			(end 0.67945 -0.3048)
			(stroke
				(width 0.1)
				(type default)
			)
			(layer "F.Fab")
		)
		(fp_line
			(start 0.12065 -0.2794)
			(end 0.12065 -0.3048)
			(stroke
				(width 0.1)
				(type default)
			)
			(layer "F.Fab")
		)
		(fp_line
			(start 0.67945 -0.3048)
			(end 0.67945 0.3048)
			(stroke
				(width 0.1)
				(type default)
			)
			(layer "F.Fab")
		)
		(fp_line
			(start 0.67945 0.3048)
			(end 0.120396 0.3048)
			(stroke
				(width 0.1)
				(type default)
			)
			(layer "F.Fab")
		)
		(pad "1" smd circle
			(at -0.40005 0)
			(size 0 0)
			(layers "F.Cu" "F.Mask" "F.Paste")
			(net "P3V3_AUX_ADC_TIC")
		)
		(pad "2" smd circle
			(at 0.40005 0)
			(size 0 0)
			(layers "F.Cu" "F.Mask" "F.Paste")
			(net "GND")
		)
	)
	(footprint ""
		(layer "F.Cu")
		(at 140.562076 -113.384584)
		(property "Reference" "U335"
			(at 0.4572 2.244852 0)
			(unlocked yes)
			(layer "F.SilkS")
			(effects
				(font
					(size 0.7874 0.5842)
					(thickness 0.1524)
				)
				(justify left)
			)
		)
		(property "Value" ""
			(at 0 0 0)
			(layer "F.Fab")
			(effects
				(font
					(size 1.27 1.27)
				)
			)
		)
		(duplicate_pad_numbers_are_jumpers no)
		(fp_line
			(start -1.733296 -1.549908)
			(end -1.733296 1.549908)
			(stroke
				(width 0.1524)
				(type default)
			)
			(layer "F.SilkS")
		)
		(fp_line
			(start -1.733296 1.549908)
			(end 1.733296 1.549908)
			(stroke
				(width 0.1524)
				(type default)
			)
			(layer "F.SilkS")
		)
		(fp_line
			(start -0.660908 -1.549908)
			(end -1.733296 -1.549908)
			(stroke
				(width 0.1524)
				(type default)
			)
			(layer "F.SilkS")
		)
		(fp_line
			(start 0 -0.889)
			(end -0.660908 -1.549908)
			(stroke
				(width 0.1524)
				(type default)
			)
			(layer "F.SilkS")
		)
		(fp_line
			(start 0.660908 -1.549908)
			(end 0 -0.889)
			(stroke
				(width 0.1524)
				(type default)
			)
			(layer "F.SilkS")
		)
		(fp_line
			(start 1.733296 -1.549908)
			(end 0.660908 -1.549908)
			(stroke
				(width 0.1524)
				(type default)
			)
			(layer "F.SilkS")
		)
		(fp_line
			(start 1.733296 1.549908)
			(end 1.733296 -1.549908)
			(stroke
				(width 0.1524)
				(type default)
			)
			(layer "F.SilkS")
		)
		(fp_poly
			(pts
				(xy -2.064512 -1.853438) (xy -2.423922 -1.494282) (xy -1.884934 -1.314704)
			)
			(stroke
				(width 0)
				(type default)
			)
			(fill yes)
			(layer "F.SilkS")
		)
		(fp_line
			(start -0.849884 -1.549908)
			(end -0.849884 1.549908)
			(stroke
				(width 0.1)
				(type default)
			)
			(layer "F.Fab")
		)
		(fp_line
			(start -0.849884 1.549908)
			(end 0.849884 1.549908)
			(stroke
				(width 0.1)
				(type default)
			)
			(layer "F.Fab")
		)
		(fp_line
			(start 0.849884 -1.549908)
			(end -0.849884 -1.549908)
			(stroke
				(width 0.1)
				(type default)
			)
			(layer "F.Fab")
		)
		(fp_line
			(start 0.849884 1.549908)
			(end 0.849884 -1.549908)
			(stroke
				(width 0.1)
				(type default)
			)
			(layer "F.Fab")
		)
		(fp_poly
			(pts
				(xy -2.4384 -1.20396) (xy -2.4384 -0.69596) (xy -1.9304 -0.94996)
			)
			(stroke
				(width 0)
				(type default)
			)
			(fill yes)
			(layer "F.Fab")
		)
		(pad "1" smd rect
			(at -1.199896 -0.94996 270)
			(size 0.5588 0.8128)
			(layers "F.Cu" "F.Mask" "F.Paste")
			(net "HP_LVC3_OCP_V3_2_PWRGD_R2")
		)
		(pad "2" smd rect
			(at -1.199896 0 270)
			(size 0.5588 0.8128)
			(layers "F.Cu" "F.Mask" "F.Paste")
			(net "OCP_V3_2_AUX_PWR_PLD_EN_R")
		)
		(pad "3" smd rect
			(at -1.199896 0.94996 270)
			(size 0.5588 0.8128)
			(layers "F.Cu" "F.Mask" "F.Paste")
			(net "GND")
		)
		(pad "4" smd rect
			(at 1.199896 0.94996 270)
			(size 0.5588 0.8128)
			(layers "F.Cu" "F.Mask" "F.Paste")
			(net "OCP_V3_2_AUX_PWR_EN_R2")
		)
		(pad "5" smd rect
			(at 1.199896 -0.94996 270)
			(size 0.5588 0.8128)
			(layers "F.Cu" "F.Mask" "F.Paste")
			(net "P3V3_AUX")
		)
	)
)
